# TIMECARD (Time Appliance Project (Time Card)) — schematic netlist excerpt (pin names and nets, part order shuffled) for the footprints in the layout excerpt that follows; sources: Cadence DE-HDL packaged netlist, KiCad conversion of R4006-B0001-02_R01.brd

DS2  OPTICAL  pkg SMC_DS_063X031_V4  page 26 : A = UNNAMED_14_OPTICAL_I11_A ; C = LED_DATOUT2
C31  CAPACITOR  0.022UF 25V 10%  pkg SMC_0402R_H022  page 32 : \1\ = XP5R0V_SS ; \2\ = XP5R0V_AGND

(kicad_pcb
	(version 20260206)
	(generator "pcbnew")
	(generator_version "10.0")
	(general
		(thickness 1.6)
		(legacy_teardrops no)
	)
	(paper "A4")
	(title_block
		(title "timecard-production-celestica-r4006 — R4006-B0001-02_R01.brd")
		(comment 1 "Time Appliance Project (Time Card) / footprints 339-340 of 1113")
	)
	(layers
		(0 "F.Cu" signal "TOP")
		(4 "In1.Cu" signal "L02_GND1")
		(6 "In2.Cu" signal "L03_SIG1")
		(8 "In3.Cu" signal "L04_GND2")
		(10 "In4.Cu" signal "L05_VCC1")
		(12 "In5.Cu" signal "L06_VCC2")
		(14 "In6.Cu" signal "L07_GND3")
		(16 "In7.Cu" signal "L08_SIG2")
		(18 "In8.Cu" signal "L09_GND4")
		(2 "B.Cu" signal "BOTTOM")
		(9 "F.Adhes" user "F.Adhesive")
		(11 "B.Adhes" user "B.Adhesive")
		(13 "F.Paste" user "Package Geometry/Pastemask Top")
		(15 "B.Paste" user "Package Geometry/Pastemask Bottom")
		(5 "F.SilkS" user "Ref Des/Silkscreen Top")
		(7 "B.SilkS" user "Ref Des/Silkscreen Bottom")
		(1 "F.Mask" user "Board Geometry/Soldermask Top")
		(3 "B.Mask" user "Board Geometry/Soldermask Bottom")
		(17 "Dwgs.User" user "User.Drawings")
		(19 "Cmts.User" user "User.Comments")
		(21 "Eco1.User" user "User.Eco1")
		(23 "Eco2.User" user "User.Eco2")
		(25 "Edge.Cuts" user "Board Geometry/Outline")
		(27 "Margin" user)
		(31 "F.CrtYd" user "Package Geometry/Place Bound Top")
		(29 "B.CrtYd" user "Package Geometry/Place Bound Bottom")
		(35 "F.Fab" user "Ref Des/Assembly Top")
		(33 "B.Fab" user "Ref Des/Assembly Bottom")
	)
	(footprint ""
		(layer "F.Cu")
		(at 141.05001 -107.849924 -90)
		(property "Reference" "DS2"
			(at 0.026924 1.36906 90)
			(unlocked yes)
			(layer "F.SilkS")
			(effects
				(font
					(size 0.635 0.4064)
					(thickness 0.1524)
				)
			)
		)
		(property "Value" ""
			(at 0 0 270)
			(layer "F.Fab")
			(effects
				(font
					(size 1.27 1.27)
				)
			)
		)
		(property "User Part Number" "PARTNUM*"
			(at 0.1778 2.422881 270)
			(unlocked yes)
			(layer "Cmts.User")
			(hide yes)
			(effects
				(font
					(size 0.786892 0.583946)
					(thickness 0.000001)
				)
			)
		)
		(property "Device Type" "OPTICAL-G170-10143-01"
			(at 0.1778 1.483081 270)
			(unlocked yes)
			(layer "F.Fab")
			(hide yes)
			(effects
				(font
					(size 0.786892 0.583946)
					(thickness 0.000001)
				)
			)
		)
		(duplicate_pad_numbers_are_jumpers no)
		(fp_line
			(start -1.3208 1.0922)
			(end -2.5908 1.0922)
			(stroke
				(width 0.1)
				(type default)
			)
			(layer "F.SilkS")
		)
		(fp_line
			(start -1.397508 0.704088)
			(end -1.397508 -0.704088)
			(stroke
				(width 0.1)
				(type default)
			)
			(layer "F.SilkS")
		)
		(fp_line
			(start 1.397508 0.704088)
			(end -1.397508 0.704088)
			(stroke
				(width 0.1)
				(type default)
			)
			(layer "F.SilkS")
		)
		(fp_line
			(start -1.9558 0.4572)
			(end -1.9558 1.7272)
			(stroke
				(width 0.1)
				(type default)
			)
			(layer "F.SilkS")
		)
		(fp_line
			(start -1.397508 -0.704088)
			(end 1.397508 -0.704088)
			(stroke
				(width 0.1)
				(type default)
			)
			(layer "F.SilkS")
		)
		(fp_line
			(start 1.397508 -0.704088)
			(end 1.397508 0.704088)
			(stroke
				(width 0.1)
				(type default)
			)
			(layer "F.SilkS")
		)
		(fp_rect
			(start 1.905508 0.704088)
			(end 1.397508 -0.704088)
			(stroke
				(width 0)
				(type default)
			)
			(fill yes)
			(layer "F.SilkS")
		)
		(fp_rect
			(start 1.905508 0.958088)
			(end -1.651508 -0.958088)
			(stroke
				(width 0)
				(type default)
			)
			(fill no)
			(layer "F.CrtYd")
		)
		(fp_line
			(start -1.5748 1.0922)
			(end -2.8448 1.0922)
			(stroke
				(width 0.1)
				(type default)
			)
			(layer "F.Fab")
		)
		(fp_line
			(start -2.2098 0.4572)
			(end -2.2098 1.7272)
			(stroke
				(width 0.1)
				(type default)
			)
			(layer "F.Fab")
		)
		(fp_line
			(start -0.850138 0.450088)
			(end 0.850138 0.450088)
			(stroke
				(width 0.1)
				(type default)
			)
			(layer "F.Fab")
		)
		(fp_line
			(start 0.850138 0.450088)
			(end 0.850138 -0.450088)
			(stroke
				(width 0.1)
				(type default)
			)
			(layer "F.Fab")
		)
		(fp_line
			(start -0.850138 -0.450088)
			(end -0.850138 0.450088)
			(stroke
				(width 0.1)
				(type default)
			)
			(layer "F.Fab")
		)
		(fp_line
			(start 0.850138 -0.450088)
			(end -0.850138 -0.450088)
			(stroke
				(width 0.1)
				(type default)
			)
			(layer "F.Fab")
		)
		(fp_rect
			(start 0.850138 0.450088)
			(end 0.342138 -0.450088)
			(stroke
				(width 0)
				(type default)
			)
			(fill yes)
			(layer "F.Fab")
		)
		(fp_text user "C"
			(at 1.455674 1.60401 0)
			(unlocked yes)
			(layer "F.SilkS")
			(effects
				(font
					(size 0.635 0.4064)
					(thickness 0.1524)
				)
			)
		)
		(fp_text user "A"
			(at -1.846326 -0.68199 0)
			(unlocked yes)
			(layer "F.SilkS")
			(effects
				(font
					(size 0.635 0.4064)
					(thickness 0.1524)
				)
			)
		)
		(fp_text user "A"
			(at -1.700276 0.096012 0)
			(unlocked yes)
			(layer "F.Fab")
			(effects
				(font
					(size 0.7874 0.5842)
					(thickness 0.1524)
				)
			)
		)
		(fp_text user "C"
			(at 1.844294 -0.80899 0)
			(unlocked yes)
			(layer "F.Fab")
			(effects
				(font
					(size 0.7874 0.5842)
					(thickness 0.1524)
				)
			)
		)
		(pad "A" smd rect
			(at -0.749808 0 270)
			(size 0.7874 0.7874)
			(layers "F.Cu" "F.Mask" "F.Paste")
			(net "UNNAMED_14_OPTICAL_I11_A")
		)
		(pad "C" smd rect
			(at 0.749808 0 270)
			(size 0.7874 0.7874)
			(layers "F.Cu" "F.Mask" "F.Paste")
			(net "LED_DATOUT2")
		)
	)
	(footprint ""
		(layer "F.Cu")
		(at 36.9824 -101.3714 180)
		(property "Reference" "C31"
			(at 4.064 1.73863 0)
			(unlocked yes)
			(layer "F.SilkS")
			(effects
				(font
					(size 0.7874 0.5842)
					(thickness 0.1524)
				)
			)
		)
		(property "Value" "VAL*"
			(at 0.0762 2.067306 180)
			(unlocked yes)
			(layer "F.Fab")
			(hide yes)
			(effects
				(font
					(size 0.7874 0.5842)
					(thickness 0.1524)
				)
			)
		)
		(property "Device Type" "CAPACITOR-G105-0B223-EK,0.022UA"
			(at 0.0508 1.127506 180)
			(unlocked yes)
			(layer "F.Fab")
			(hide yes)
			(effects
				(font
					(size 0.7874 0.5842)
					(thickness 0.1524)
				)
			)
		)
		(property "User Part Number" "PARTNUM*"
			(at 0.1016 4.023106 180)
			(unlocked yes)
			(layer "Cmts.User")
			(hide yes)
			(effects
				(font
					(size 0.7874 0.5842)
					(thickness 0.1524)
				)
			)
		)
		(property "Tolerance" "TOL*"
			(at 0.0762 3.032506 180)
			(unlocked yes)
			(layer "Cmts.User")
			(hide yes)
			(effects
				(font
					(size 0.7874 0.5842)
					(thickness 0.1524)
				)
			)
		)
		(duplicate_pad_numbers_are_jumpers no)
		(fp_line
			(start 1.143 0.5588)
			(end 1.143 -0.5588)
			(stroke
				(width 0.1)
				(type default)
			)
			(layer "F.SilkS")
		)
		(fp_line
			(start 1.143 -0.5588)
			(end -1.143 -0.5588)
			(stroke
				(width 0.1)
				(type default)
			)
			(layer "F.SilkS")
		)
		(fp_line
			(start -1.143 0.5588)
			(end 1.143 0.5588)
			(stroke
				(width 0.1)
				(type default)
			)
			(layer "F.SilkS")
		)
		(fp_line
			(start -1.143 -0.5588)
			(end -1.143 0.5588)
			(stroke
				(width 0.1)
				(type default)
			)
			(layer "F.SilkS")
		)
		(fp_rect
			(start -1.143 0.5588)
			(end 1.143 -0.5588)
			(stroke
				(width 0)
				(type default)
			)
			(fill no)
			(layer "F.CrtYd")
		)
		(fp_line
			(start 0.508 0.3048)
			(end 0.508 -0.3048)
			(stroke
				(width 0.1)
				(type default)
			)
			(layer "F.Fab")
		)
		(fp_line
			(start 0.508 -0.3048)
			(end -0.508 -0.3048)
			(stroke
				(width 0.1)
				(type default)
			)
			(layer "F.Fab")
		)
		(fp_line
			(start -0.508 0.3048)
			(end 0.508 0.3048)
			(stroke
				(width 0.1)
				(type default)
			)
			(layer "F.Fab")
		)
		(fp_line
			(start -0.508 -0.3048)
			(end -0.508 0.3048)
			(stroke
				(width 0.1)
				(type default)
			)
			(layer "F.Fab")
		)
		(pad "1" smd rect
			(at -0.5334 0 180)
			(size 0.7112 0.6096)
			(layers "F.Cu" "F.Mask" "F.Paste")
			(net "XP5R0V_SS")
		)
		(pad "2" smd rect
			(at 0.5334 0 180)
			(size 0.7112 0.6096)
			(layers "F.Cu" "F.Mask" "F.Paste")
			(net "XP5R0V_AGND")
		)
		(zone
			(layer "F.Cu")
			(hatch none 0.5)
			(connect_pads
				(clearance 0)
			)
			(min_thickness 0.25)
			(keepout
				(tracks allowed)
				(vias not_allowed)
				(pads allowed)
				(copperpour not_allowed)
				(footprints allowed)
			)
			(placement
				(enabled no)
				(sheetname "")
			)
			(fill
				(thermal_gap 0.5)
				(thermal_bridge_width 0.5)
				(island_removal_mode 0)
			)
			(polygon
				(pts
					(xy 37.0586 -101.6762) (xy 36.9062 -101.6762) (xy 36.9062 -101.0666) (xy 37.0586 -101.0666)
				)
			)
		)
	)
)
